(kicad_pcb
	(version 20260206)
	(generator "pcbnew")
	(generator_version "10.0")
	(general
		(thickness 1.6)
		(legacy_teardrops no)
	)
	(paper "A4")
	(title_block
		(title "01162023_DA0F0TEBIF0_F0T_Expander_BD_F_brd_V02_OCP.brd")
		(comment 1 "Grand Teton / footprints 2136-2141 of 9728")
	)
	(layers
		(0 "F.Cu" signal "TOP")
		(4 "In1.Cu" signal "GND")
		(6 "In2.Cu" signal "VCC")
		(8 "In3.Cu" signal "VCC1")
		(10 "In4.Cu" signal "GND1")
		(12 "In5.Cu" signal "IN1")
		(14 "In6.Cu" signal "GND2")
		(16 "In7.Cu" signal "IN2")
		(18 "In8.Cu" signal "GND3")
		(20 "In9.Cu" signal "IN3")
		(22 "In10.Cu" signal "GND4")
		(24 "In11.Cu" signal "IN4")
		(26 "In12.Cu" signal "GND5")
		(28 "In13.Cu" signal "IN5")
		(30 "In14.Cu" signal "GND6")
		(32 "In15.Cu" signal "IN6")
		(34 "In16.Cu" signal "GND7")
		(2 "B.Cu" signal "BOTTOM")
		(9 "F.Adhes" user "F.Adhesive")
		(11 "B.Adhes" user "B.Adhesive")
		(13 "F.Paste" user "Package Geometry/Pastemask Top")
		(15 "B.Paste" user "Package Geometry/Pastemask Bottom")
		(5 "F.SilkS" user "Ref Des/Silkscreen Top")
		(7 "B.SilkS" user "Ref Des/Silkscreen Bottom")
		(1 "F.Mask" user "Board Geometry/Soldermask Top")
		(3 "B.Mask" user "Board Geometry/Soldermask Bottom")
		(17 "Dwgs.User" user "User.Drawings")
		(19 "Cmts.User" user "User.Comments")
		(21 "Eco1.User" user "User.Eco1")
		(23 "Eco2.User" user "User.Eco2")
		(25 "Edge.Cuts" user "Board Geometry/Outline")
		(27 "Margin" user)
		(31 "F.CrtYd" user "Package Geometry/Place Bound Top")
		(29 "B.CrtYd" user "Package Geometry/Place Bound Bottom")
		(35 "F.Fab" user "Ref Des/Assembly Top")
		(33 "B.Fab" user "Ref Des/Assembly Bottom")
	)
	(footprint ""
		(layer "F.Cu")
		(at 323.067934 -289.230816 90)
		(property "Reference" "R3985"
			(at 0 0 90)
			(layer "F.SilkS")
			(hide yes)
			(effects
				(font
					(size 1.27 1.27)
				)
			)
		)
		(property "Value" ""
			(at 0 0 90)
			(layer "F.Fab")
			(effects
				(font
					(size 1.27 1.27)
				)
			)
		)
		(duplicate_pad_numbers_are_jumpers no)
		(fp_line
			(start 0.7874 -0.4064)
			(end 0.7874 0.4064)
			(stroke
				(width 0.1524)
				(type default)
			)
			(layer "F.SilkS")
		)
		(fp_line
			(start -0.7874 -0.4064)
			(end 0.7874 -0.4064)
			(stroke
				(width 0.1524)
				(type default)
			)
			(layer "F.SilkS")
		)
		(fp_line
			(start 0.7874 0.4064)
			(end -0.7874 0.4064)
			(stroke
				(width 0.1524)
				(type default)
			)
			(layer "F.SilkS")
		)
		(fp_line
			(start -0.7874 0.4064)
			(end -0.7874 -0.4064)
			(stroke
				(width 0.1524)
				(type default)
			)
			(layer "F.SilkS")
		)
		(fp_line
			(start -0.12065 -0.305054)
			(end -0.12065 -0.2794)
			(stroke
				(width 0.1)
				(type default)
			)
			(layer "F.Fab")
		)
		(fp_line
			(start -0.67945 -0.305054)
			(end -0.12065 -0.305054)
			(stroke
				(width 0.1)
				(type default)
			)
			(layer "F.Fab")
		)
		(fp_line
			(start 0.67945 -0.3048)
			(end 0.67945 0.3048)
			(stroke
				(width 0.1)
				(type default)
			)
			(layer "F.Fab")
		)
		(fp_line
			(start 0.12065 -0.3048)
			(end 0.67945 -0.3048)
			(stroke
				(width 0.1)
				(type default)
			)
			(layer "F.Fab")
		)
		(fp_line
			(start 0.12065 -0.2794)
			(end 0.12065 -0.3048)
			(stroke
				(width 0.1)
				(type default)
			)
			(layer "F.Fab")
		)
		(fp_line
			(start -0.12065 -0.2794)
			(end 0.12065 -0.2794)
			(stroke
				(width 0.1)
				(type default)
			)
			(layer "F.Fab")
		)
		(fp_line
			(start 0.120396 0.2794)
			(end -0.12065 0.2794)
			(stroke
				(width 0.1)
				(type default)
			)
			(layer "F.Fab")
		)
		(fp_line
			(start -0.12065 0.2794)
			(end -0.12065 0.3048)
			(stroke
				(width 0.1)
				(type default)
			)
			(layer "F.Fab")
		)
		(fp_line
			(start 0.67945 0.3048)
			(end 0.120396 0.3048)
			(stroke
				(width 0.1)
				(type default)
			)
			(layer "F.Fab")
		)
		(fp_line
			(start 0.120396 0.3048)
			(end 0.120396 0.2794)
			(stroke
				(width 0.1)
				(type default)
			)
			(layer "F.Fab")
		)
		(fp_line
			(start -0.12065 0.3048)
			(end -0.67945 0.3048)
			(stroke
				(width 0.1)
				(type default)
			)
			(layer "F.Fab")
		)
		(fp_line
			(start -0.67945 0.3048)
			(end -0.67945 -0.305054)
			(stroke
				(width 0.1)
				(type default)
			)
			(layer "F.Fab")
		)
		(pad "1" smd circle
			(at -0.40005 0 90)
			(size 0 0)
			(layers "F.Cu" "F.Mask" "F.Paste")
			(net "SMB_PEX2_FPGA_SCL")
		)
		(pad "2" smd circle
			(at 0.40005 0 90)
			(size 0 0)
			(layers "F.Cu" "F.Mask" "F.Paste")
			(net "SMB_PEX2_HOST_LS_SCL")
		)
	)
	(footprint ""
		(layer "F.Cu")
		(at 106.035094 -397.512286 -90)
		(property "Reference" "R5446"
			(at 0 0 270)
			(layer "F.SilkS")
			(hide yes)
			(effects
				(font
					(size 1.27 1.27)
				)
			)
		)
		(property "Value" ""
			(at 0 0 270)
			(layer "F.Fab")
			(effects
				(font
					(size 1.27 1.27)
				)
			)
		)
		(duplicate_pad_numbers_are_jumpers no)
		(fp_line
			(start -0.7874 0.4064)
			(end -0.7874 -0.4064)
			(stroke
				(width 0.1524)
				(type default)
			)
			(layer "F.SilkS")
		)
		(fp_line
			(start 0.7874 0.4064)
			(end -0.7874 0.4064)
			(stroke
				(width 0.1524)
				(type default)
			)
			(layer "F.SilkS")
		)
		(fp_line
			(start -0.7874 -0.4064)
			(end 0.7874 -0.4064)
			(stroke
				(width 0.1524)
				(type default)
			)
			(layer "F.SilkS")
		)
		(fp_line
			(start 0.7874 -0.4064)
			(end 0.7874 0.4064)
			(stroke
				(width 0.1524)
				(type default)
			)
			(layer "F.SilkS")
		)
		(fp_line
			(start -0.67945 0.3048)
			(end -0.67945 -0.305054)
			(stroke
				(width 0.1)
				(type default)
			)
			(layer "F.Fab")
		)
		(fp_line
			(start -0.12065 0.3048)
			(end -0.67945 0.3048)
			(stroke
				(width 0.1)
				(type default)
			)
			(layer "F.Fab")
		)
		(fp_line
			(start 0.120396 0.3048)
			(end 0.120396 0.2794)
			(stroke
				(width 0.1)
				(type default)
			)
			(layer "F.Fab")
		)
		(fp_line
			(start 0.67945 0.3048)
			(end 0.120396 0.3048)
			(stroke
				(width 0.1)
				(type default)
			)
			(layer "F.Fab")
		)
		(fp_line
			(start -0.12065 0.2794)
			(end -0.12065 0.3048)
			(stroke
				(width 0.1)
				(type default)
			)
			(layer "F.Fab")
		)
		(fp_line
			(start 0.120396 0.2794)
			(end -0.12065 0.2794)
			(stroke
				(width 0.1)
				(type default)
			)
			(layer "F.Fab")
		)
		(fp_line
			(start -0.12065 -0.2794)
			(end 0.12065 -0.2794)
			(stroke
				(width 0.1)
				(type default)
			)
			(layer "F.Fab")
		)
		(fp_line
			(start 0.12065 -0.2794)
			(end 0.12065 -0.3048)
			(stroke
				(width 0.1)
				(type default)
			)
			(layer "F.Fab")
		)
		(fp_line
			(start 0.12065 -0.3048)
			(end 0.67945 -0.3048)
			(stroke
				(width 0.1)
				(type default)
			)
			(layer "F.Fab")
		)
		(fp_line
			(start 0.67945 -0.3048)
			(end 0.67945 0.3048)
			(stroke
				(width 0.1)
				(type default)
			)
			(layer "F.Fab")
		)
		(fp_line
			(start -0.67945 -0.305054)
			(end -0.12065 -0.305054)
			(stroke
				(width 0.1)
				(type default)
			)
			(layer "F.Fab")
		)
		(fp_line
			(start -0.12065 -0.305054)
			(end -0.12065 -0.2794)
			(stroke
				(width 0.1)
				(type default)
			)
			(layer "F.Fab")
		)
		(pad "1" smd circle
			(at -0.40005 0 270)
			(size 0 0)
			(layers "F.Cu" "F.Mask" "F.Paste")
			(net "P3V3_AUX")
		)
		(pad "2" smd circle
			(at 0.40005 0 270)
			(size 0 0)
			(layers "F.Cu" "F.Mask" "F.Paste")
			(net "RST_BIC_USB_HUB_R1_N")
		)
	)
	(footprint ""
		(layer "F.Cu")
		(at 228.024944 -98.36912 90)
		(property "Reference" "R4456"
			(at 0 0 90)
			(layer "F.SilkS")
			(hide yes)
			(effects
				(font
					(size 1.27 1.27)
				)
			)
		)
		(property "Value" ""
			(at 0 0 90)
			(layer "F.Fab")
			(effects
				(font
					(size 1.27 1.27)
				)
			)
		)
		(duplicate_pad_numbers_are_jumpers no)
		(fp_line
			(start 0.7874 -0.4064)
			(end 0.7874 0.4064)
			(stroke
				(width 0.1524)
				(type default)
			)
			(layer "F.SilkS")
		)
		(fp_line
			(start -0.7874 -0.4064)
			(end 0.7874 -0.4064)
			(stroke
				(width 0.1524)
				(type default)
			)
			(layer "F.SilkS")
		)
		(fp_line
			(start 0.7874 0.4064)
			(end -0.7874 0.4064)
			(stroke
				(width 0.1524)
				(type default)
			)
			(layer "F.SilkS")
		)
		(fp_line
			(start -0.7874 0.4064)
			(end -0.7874 -0.4064)
			(stroke
				(width 0.1524)
				(type default)
			)
			(layer "F.SilkS")
		)
		(fp_line
			(start -0.12065 -0.305054)
			(end -0.12065 -0.2794)
			(stroke
				(width 0.1)
				(type default)
			)
			(layer "F.Fab")
		)
		(fp_line
			(start -0.67945 -0.305054)
			(end -0.12065 -0.305054)
			(stroke
				(width 0.1)
				(type default)
			)
			(layer "F.Fab")
		)
		(fp_line
			(start 0.67945 -0.3048)
			(end 0.67945 0.3048)
			(stroke
				(width 0.1)
				(type default)
			)
			(layer "F.Fab")
		)
		(fp_line
			(start 0.12065 -0.3048)
			(end 0.67945 -0.3048)
			(stroke
				(width 0.1)
				(type default)
			)
			(layer "F.Fab")
		)
		(fp_line
			(start 0.12065 -0.2794)
			(end 0.12065 -0.3048)
			(stroke
				(width 0.1)
				(type default)
			)
			(layer "F.Fab")
		)
		(fp_line
			(start -0.12065 -0.2794)
			(end 0.12065 -0.2794)
			(stroke
				(width 0.1)
				(type default)
			)
			(layer "F.Fab")
		)
		(fp_line
			(start 0.120396 0.2794)
			(end -0.12065 0.2794)
			(stroke
				(width 0.1)
				(type default)
			)
			(layer "F.Fab")
		)
		(fp_line
			(start -0.12065 0.2794)
			(end -0.12065 0.3048)
			(stroke
				(width 0.1)
				(type default)
			)
			(layer "F.Fab")
		)
		(fp_line
			(start 0.67945 0.3048)
			(end 0.120396 0.3048)
			(stroke
				(width 0.1)
				(type default)
			)
			(layer "F.Fab")
		)
		(fp_line
			(start 0.120396 0.3048)
			(end 0.120396 0.2794)
			(stroke
				(width 0.1)
				(type default)
			)
			(layer "F.Fab")
		)
		(fp_line
			(start -0.12065 0.3048)
			(end -0.67945 0.3048)
			(stroke
				(width 0.1)
				(type default)
			)
			(layer "F.Fab")
		)
		(fp_line
			(start -0.67945 0.3048)
			(end -0.67945 -0.305054)
			(stroke
				(width 0.1)
				(type default)
			)
			(layer "F.Fab")
		)
		(pad "1" smd circle
			(at -0.40005 0 90)
			(size 0 0)
			(layers "F.Cu" "F.Mask" "F.Paste")
			(net "HP_NIC3_EN")
		)
		(pad "2" smd circle
			(at 0.40005 0 90)
			(size 0 0)
			(layers "F.Cu" "F.Mask" "F.Paste")
			(net "P12V_NIC3_EN_R")
		)
	)
	(footprint ""
		(layer "F.Cu")
		(at 454.930002 -250.20524)
		(property "Reference" "C4433"
			(at 0 0 0)
			(layer "F.SilkS")
			(hide yes)
			(effects
				(font
					(size 1.27 1.27)
				)
			)
		)
		(property "Value" ""
			(at 0 0 0)
			(layer "F.Fab")
			(effects
				(font
					(size 1.27 1.27)
				)
			)
		)
		(duplicate_pad_numbers_are_jumpers no)
		(fp_line
			(start -0.7874 -0.4064)
			(end 0.7874 -0.4064)
			(stroke
				(width 0.1524)
				(type default)
			)
			(layer "F.SilkS")
		)
		(fp_line
			(start -0.7874 0.4064)
			(end -0.7874 -0.4064)
			(stroke
				(width 0.1524)
				(type default)
			)
			(layer "F.SilkS")
		)
		(fp_line
			(start 0.7874 -0.4064)
			(end 0.7874 0.4064)
			(stroke
				(width 0.1524)
				(type default)
			)
			(layer "F.SilkS")
		)
		(fp_line
			(start 0.7874 0.4064)
			(end -0.7874 0.4064)
			(stroke
				(width 0.1524)
				(type default)
			)
			(layer "F.SilkS")
		)
		(fp_line
			(start -0.67945 -0.305054)
			(end -0.12065 -0.305054)
			(stroke
				(width 0.1)
				(type default)
			)
			(layer "F.Fab")
		)
		(fp_line
			(start -0.67945 0.3048)
			(end -0.67945 -0.305054)
			(stroke
				(width 0.1)
				(type default)
			)
			(layer "F.Fab")
		)
		(fp_line
			(start -0.12065 -0.305054)
			(end -0.12065 -0.2794)
			(stroke
				(width 0.1)
				(type default)
			)
			(layer "F.Fab")
		)
		(fp_line
			(start -0.12065 -0.2794)
			(end 0.12065 -0.2794)
			(stroke
				(width 0.1)
				(type default)
			)
			(layer "F.Fab")
		)
		(fp_line
			(start -0.12065 0.2794)
			(end -0.12065 0.3048)
			(stroke
				(width 0.1)
				(type default)
			)
			(layer "F.Fab")
		)
		(fp_line
			(start -0.12065 0.3048)
			(end -0.67945 0.3048)
			(stroke
				(width 0.1)
				(type default)
			)
			(layer "F.Fab")
		)
		(fp_line
			(start 0.120396 0.2794)
			(end -0.12065 0.2794)
			(stroke
				(width 0.1)
				(type default)
			)
			(layer "F.Fab")
		)
		(fp_line
			(start 0.120396 0.3048)
			(end 0.120396 0.2794)
			(stroke
				(width 0.1)
				(type default)
			)
			(layer "F.Fab")
		)
		(fp_line
			(start 0.12065 -0.3048)
			(end 0.67945 -0.3048)
			(stroke
				(width 0.1)
				(type default)
			)
			(layer "F.Fab")
		)
		(fp_line
			(start 0.12065 -0.2794)
			(end 0.12065 -0.3048)
			(stroke
				(width 0.1)
				(type default)
			)
			(layer "F.Fab")
		)
		(fp_line
			(start 0.67945 -0.3048)
			(end 0.67945 0.3048)
			(stroke
				(width 0.1)
				(type default)
			)
			(layer "F.Fab")
		)
		(fp_line
			(start 0.67945 0.3048)
			(end 0.120396 0.3048)
			(stroke
				(width 0.1)
				(type default)
			)
			(layer "F.Fab")
		)
		(pad "1" smd circle
			(at -0.40005 0)
			(size 0 0)
			(layers "F.Cu" "F.Mask" "F.Paste")
			(net "PEX3_P1V8_PLL_EN")
		)
		(pad "2" smd circle
			(at 0.40005 0)
			(size 0 0)
			(layers "F.Cu" "F.Mask" "F.Paste")
			(net "GND")
		)
	)
	(footprint ""
		(layer "F.Cu")
		(at 123.71324 -139.376404)
		(property "Reference" "R857"
			(at 0 0 0)
			(layer "F.SilkS")
			(hide yes)
			(effects
				(font
					(size 1.27 1.27)
				)
			)
		)
		(property "Value" ""
			(at 0 0 0)
			(layer "F.Fab")
			(effects
				(font
					(size 1.27 1.27)
				)
			)
		)
		(duplicate_pad_numbers_are_jumpers no)
		(fp_line
			(start -0.7874 -0.4064)
			(end 0.7874 -0.4064)
			(stroke
				(width 0.1524)
				(type default)
			)
			(layer "F.SilkS")
		)
		(fp_line
			(start -0.7874 0.4064)
			(end -0.7874 -0.4064)
			(stroke
				(width 0.1524)
				(type default)
			)
			(layer "F.SilkS")
		)
		(fp_line
			(start 0.7874 -0.4064)
			(end 0.7874 0.4064)
			(stroke
				(width 0.1524)
				(type default)
			)
			(layer "F.SilkS")
		)
		(fp_line
			(start 0.7874 0.4064)
			(end -0.7874 0.4064)
			(stroke
				(width 0.1524)
				(type default)
			)
			(layer "F.SilkS")
		)
		(fp_line
			(start -0.67945 -0.305054)
			(end -0.12065 -0.305054)
			(stroke
				(width 0.1)
				(type default)
			)
			(layer "F.Fab")
		)
		(fp_line
			(start -0.67945 0.3048)
			(end -0.67945 -0.305054)
			(stroke
				(width 0.1)
				(type default)
			)
			(layer "F.Fab")
		)
		(fp_line
			(start -0.12065 -0.305054)
			(end -0.12065 -0.2794)
			(stroke
				(width 0.1)
				(type default)
			)
			(layer "F.Fab")
		)
		(fp_line
			(start -0.12065 -0.2794)
			(end 0.12065 -0.2794)
			(stroke
				(width 0.1)
				(type default)
			)
			(layer "F.Fab")
		)
		(fp_line
			(start -0.12065 0.2794)
			(end -0.12065 0.3048)
			(stroke
				(width 0.1)
				(type default)
			)
			(layer "F.Fab")
		)
		(fp_line
			(start -0.12065 0.3048)
			(end -0.67945 0.3048)
			(stroke
				(width 0.1)
				(type default)
			)
			(layer "F.Fab")
		)
		(fp_line
			(start 0.120396 0.2794)
			(end -0.12065 0.2794)
			(stroke
				(width 0.1)
				(type default)
			)
			(layer "F.Fab")
		)
		(fp_line
			(start 0.120396 0.3048)
			(end 0.120396 0.2794)
			(stroke
				(width 0.1)
				(type default)
			)
			(layer "F.Fab")
		)
		(fp_line
			(start 0.12065 -0.3048)
			(end 0.67945 -0.3048)
			(stroke
				(width 0.1)
				(type default)
			)
			(layer "F.Fab")
		)
		(fp_line
			(start 0.12065 -0.2794)
			(end 0.12065 -0.3048)
			(stroke
				(width 0.1)
				(type default)
			)
			(layer "F.Fab")
		)
		(fp_line
			(start 0.67945 -0.3048)
			(end 0.67945 0.3048)
			(stroke
				(width 0.1)
				(type default)
			)
			(layer "F.Fab")
		)
		(fp_line
			(start 0.67945 0.3048)
			(end 0.120396 0.3048)
			(stroke
				(width 0.1)
				(type default)
			)
			(layer "F.Fab")
		)
		(pad "1" smd circle
			(at -0.40005 0)
			(size 0 0)
			(layers "F.Cu" "F.Mask" "F.Paste")
			(net "P3V3_AUX")
		)
		(pad "2" smd circle
			(at 0.40005 0)
			(size 0 0)
			(layers "F.Cu" "F.Mask" "F.Paste")
			(net "PWRGD_P12V_NIC2")
		)
	)
	(footprint ""
		(layer "F.Cu")
		(at 102.1588 -201.6252)
		(property "Reference" "C4445"
			(at 0 0 0)
			(layer "F.SilkS")
			(hide yes)
			(effects
				(font
					(size 1.27 1.27)
				)
			)
		)
		(property "Value" ""
			(at 0 0 0)
			(layer "F.Fab")
			(effects
				(font
					(size 1.27 1.27)
				)
			)
		)
		(duplicate_pad_numbers_are_jumpers no)
		(fp_line
			(start -1.2954 -0.5842)
			(end 1.2954 -0.5842)
			(stroke
				(width 0.1524)
				(type default)
			)
			(layer "F.SilkS")
		)
		(fp_line
			(start -1.2954 0.5842)
			(end -1.2954 -0.5842)
			(stroke
				(width 0.1524)
				(type default)
			)
			(layer "F.SilkS")
		)
		(fp_line
			(start 1.2954 -0.5842)
			(end 1.2954 0.5842)
			(stroke
				(width 0.1524)
				(type default)
			)
			(layer "F.SilkS")
		)
		(fp_line
			(start 1.2954 0.5842)
			(end -1.2954 0.5842)
			(stroke
				(width 0.1524)
				(type default)
			)
			(layer "F.SilkS")
		)
		(fp_line
			(start -1.1938 -0.4064)
			(end -0.8636 -0.4064)
			(stroke
				(width 0.1)
				(type default)
			)
			(layer "F.Fab")
		)
		(fp_line
			(start -1.1938 0.4064)
			(end -1.1938 -0.4064)
			(stroke
				(width 0.1)
				(type default)
			)
			(layer "F.Fab")
		)
		(fp_line
			(start -0.8636 -0.4572)
			(end 0.8636 -0.4572)
			(stroke
				(width 0.1)
				(type default)
			)
			(layer "F.Fab")
		)
		(fp_line
			(start -0.8636 -0.4064)
			(end -0.8636 -0.4572)
			(stroke
				(width 0.1)
				(type default)
			)
			(layer "F.Fab")
		)
		(fp_line
			(start -0.8636 0.4064)
			(end -1.1938 0.4064)
			(stroke
				(width 0.1)
				(type default)
			)
			(layer "F.Fab")
		)
		(fp_line
			(start -0.8636 0.4572)
			(end -0.8636 0.4064)
			(stroke
				(width 0.1)
				(type default)
			)
			(layer "F.Fab")
		)
		(fp_line
			(start 0.8636 -0.4572)
			(end 0.8636 -0.4064)
			(stroke
				(width 0.1)
				(type default)
			)
			(layer "F.Fab")
		)
		(fp_line
			(start 0.8636 -0.4064)
			(end 1.1938 -0.4064)
			(stroke
				(width 0.1)
				(type default)
			)
			(layer "F.Fab")
		)
		(fp_line
			(start 0.8636 0.4064)
			(end 0.8636 0.4572)
			(stroke
				(width 0.1)
				(type default)
			)
			(layer "F.Fab")
		)
		(fp_line
			(start 0.8636 0.4572)
			(end -0.8636 0.4572)
			(stroke
				(width 0.1)
				(type default)
			)
			(layer "F.Fab")
		)
		(fp_line
			(start 1.1938 -0.4064)
			(end 1.1938 0.4064)
			(stroke
				(width 0.1)
				(type default)
			)
			(layer "F.Fab")
		)
		(fp_line
			(start 1.1938 0.4064)
			(end 0.8636 0.4064)
			(stroke
				(width 0.1)
				(type default)
			)
			(layer "F.Fab")
		)
		(pad "1" smd rect
			(at -0.7366 0 270)
			(size 0.7112 0.8128)
			(layers "F.Cu" "F.Mask" "F.Paste")
			(net "P3V3_AUX")
		)
		(pad "2" smd rect
			(at 0.7366 0 270)
			(size 0.7112 0.8128)
			(layers "F.Cu" "F.Mask" "F.Paste")
			(net "GND")
		)
	)
)
